(kicad_pcb
	(version 20241229)
	(generator "pcbnew")
	(generator_version "9.0")
	(general
		(thickness 1.258)
		(legacy_teardrops no)
	)
	(paper "A4")
	(title_block
		(date "2024-05-27")
		(rev "1.1.2")
		(comment 9 "footprint 36 of 64 (U1), pads 1-82 of 82")
	)
	(layers
		(0 "F.Cu" signal)
		(4 "In1.Cu" power)
		(6 "In2.Cu" power)
		(8 "In3.Cu" signal)
		(10 "In4.Cu" signal)
		(2 "B.Cu" signal)
		(9 "F.Adhes" user "F.Adhesive")
		(11 "B.Adhes" user "B.Adhesive")
		(13 "F.Paste" user)
		(15 "B.Paste" user)
		(5 "F.SilkS" user "F.Silkscreen")
		(7 "B.SilkS" user "B.Silkscreen")
		(1 "F.Mask" user)
		(3 "B.Mask" user)
		(17 "Dwgs.User" user "User.Drawings")
		(19 "Cmts.User" user "User.Comments")
		(21 "Eco1.User" user "User.Eco1")
		(23 "Eco2.User" user "User.Eco2")
		(25 "Edge.Cuts" user)
		(27 "Margin" user)
		(31 "F.CrtYd" user "F.Courtyard")
		(29 "B.CrtYd" user "B.Courtyard")
		(35 "F.Fab" user)
		(33 "B.Fab" user)
	)
	(footprint "antmicro-footprints:BGA-82_11x9mm_Layout13x11_P0.8mm_DDR5_MO-210-AN"
		(locked yes)
		(layer "F.Cu")
		(at 151.225 85.25 -90)
		(property "Reference" "U1"
			(at -4.99 5.965 0)
			(layer "F.SilkS")
			(effects
				(font
					(size 0.7 0.7)
					(thickness 0.15)
				)
				(justify left bottom)
			)
		)
		(property "Value" "MT60B2G8HB-48B_A"
			(at -14.94 6.93 270)
			(layer "F.Fab")
			(hide yes)
			(effects
				(font
					(size 0.7 0.7)
					(thickness 0.15)
				)
				(justify left bottom)
			)
		)
		(property "Description" "DRAM, SDRAM, 16 Gbit, 2G x 8bit, FBGA, 82 Pins"
			(at 0 0 270)
			(layer "F.Fab")
			(hide yes)
			(effects
				(font
					(size 1.27 1.27)
					(thickness 0.15)
				)
			)
		)
		(property "Author" "Antmicro"
			(at 65.975 236.475 0)
			(layer "F.Fab")
			(hide yes)
			(effects
				(font
					(size 1 1)
					(thickness 0.15)
				)
			)
		)
		(property "License" "Apache-2.0"
			(at 65.975 236.475 0)
			(layer "F.Fab")
			(hide yes)
			(effects
				(font
					(size 1 1)
					(thickness 0.15)
				)
			)
		)
		(property "MPN" "MT60B2G8HB-48B:A"
			(at 65.975 236.475 0)
			(layer "F.Fab")
			(hide yes)
			(effects
				(font
					(size 1 1)
					(thickness 0.15)
				)
			)
		)
		(property "Manufacturer" "Micron Technology"
			(at 65.975 236.475 0)
			(layer "F.Fab")
			(hide yes)
			(effects
				(font
					(size 1 1)
					(thickness 0.15)
				)
			)
		)
		(sheetname "DDR5")
		(sheetfile "ddr5.kicad_sch")
		(attr smd)
		(pad "A1" smd circle
			(at -4 -4.8 270)
			(size 0.45 0.45)
			(layers "F.Cu" "F.Mask" "F.Paste")
			(net 219 "unconnected-(U1-DNU-PadA1)")
			(pinfunction "DNU")
			(pintype "no_connect")
		)
		(pad "A2" smd circle
			(at -3.202 -4.8 270)
			(size 0.45 0.45)
			(layers "F.Cu" "F.Mask" "F.Paste")
			(net 65 "/DDR5/R_LBDQ")
			(pinfunction "LBDQ")
			(pintype "input")
		)
		(pad "A3" smd circle
			(at -2.4 -4.8 270)
			(size 0.45 0.45)
			(layers "F.Cu" "F.Mask" "F.Paste")
			(net 1 "GND")
			(pinfunction "VSS")
			(pintype "passive")
		)
		(pad "A4" smd circle
			(at -1.601 -4.8 270)
			(size 0.45 0.45)
			(layers "F.Cu" "F.Mask" "F.Paste")
			(net 19 "VPP")
			(pinfunction "VPP")
			(pintype "power_in")
		)
		(pad "A8" smd circle
			(at 1.6 -4.8 270)
			(size 0.45 0.45)
			(layers "F.Cu" "F.Mask" "F.Paste")
			(net 61 "/DDR5/ZQ")
			(pinfunction "ZQ")
			(pintype "input")
		)
		(pad "A9" smd circle
			(at 2.398 -4.8 270)
			(size 0.45 0.45)
			(layers "F.Cu" "F.Mask" "F.Paste")
			(net 1 "GND")
			(pinfunction "VSS")
			(pintype "passive")
		)
		(pad "A10" smd circle
			(at 3.2 -4.8 270)
			(size 0.45 0.45)
			(layers "F.Cu" "F.Mask" "F.Paste")
			(net 66 "/DDR5/R_LBDQS")
			(pinfunction "LBDQS")
			(pintype "input")
		)
		(pad "A11" smd circle
			(at 3.999 -4.8 270)
			(size 0.45 0.45)
			(layers "F.Cu" "F.Mask" "F.Paste")
			(net 220 "unconnected-(U1-DNU-PadA11)")
			(pinfunction "DNU")
			(pintype "no_connect")
		)
		(pad "B2" smd circle
			(at -3.202 -4 270)
			(size 0.45 0.45)
			(layers "F.Cu" "F.Mask" "F.Paste")
			(net 18 "VDD")
			(pinfunction "VDD")
			(pintype "power_in")
		)
		(pad "B3" smd circle
			(at -2.4 -4 270)
			(size 0.45 0.45)
			(layers "F.Cu" "F.Mask" "F.Paste")
			(net 2 "VDDQ")
			(pinfunction "VDDQ")
			(pintype "power_in")
		)
		(pad "B4" smd circle
			(at -1.601 -4 270)
			(size 0.45 0.45)
			(layers "F.Cu" "F.Mask" "F.Paste")
			(net 21 "DQ2")
			(pinfunction "DQ2")
			(pintype "bidirectional")
		)
		(pad "B8" smd circle
			(at 1.6 -4 270)
			(size 0.45 0.45)
			(layers "F.Cu" "F.Mask" "F.Paste")
			(net 20 "DQ3")
			(pinfunction "DQ3")
			(pintype "bidirectional")
		)
		(pad "B9" smd circle
			(at 2.398 -4 270)
			(size 0.45 0.45)
			(layers "F.Cu" "F.Mask" "F.Paste")
			(net 2 "VDDQ")
			(pinfunction "VDDQ")
			(pintype "power_in")
		)
		(pad "B10" smd circle
			(at 3.2 -4 270)
			(size 0.45 0.45)
			(layers "F.Cu" "F.Mask" "F.Paste")
			(net 18 "VDD")
			(pinfunction "VDD")
			(pintype "power_in")
		)
		(pad "C2" smd circle
			(at -3.202 -3.202 270)
			(size 0.45 0.45)
			(layers "F.Cu" "F.Mask" "F.Paste")
			(net 1 "GND")
			(pinfunction "VSS")
			(pintype "passive")
		)
		(pad "C3" smd circle
			(at -2.4 -3.202 270)
			(size 0.45 0.45)
			(layers "F.Cu" "F.Mask" "F.Paste")
			(net 25 "DQ0")
			(pinfunction "DQ0")
			(pintype "bidirectional")
		)
		(pad "C4" smd circle
			(at -1.601 -3.202 270)
			(size 0.45 0.45)
			(layers "F.Cu" "F.Mask" "F.Paste")
			(net 26 "DQS_P")
			(pinfunction "DQS_T")
			(pintype "bidirectional")
		)
		(pad "C8" smd circle
			(at 1.6 -3.202 270)
			(size 0.45 0.45)
			(layers "F.Cu" "F.Mask" "F.Paste")
			(net 37 "TDQS_P")
			(pinfunction "TDQS_T")
			(pintype "output")
		)
		(pad "C9" smd circle
			(at 2.398 -3.202 270)
			(size 0.45 0.45)
			(layers "F.Cu" "F.Mask" "F.Paste")
			(net 23 "DQ1")
			(pinfunction "DQ1")
			(pintype "bidirectional")
		)
		(pad "C10" smd circle
			(at 3.2 -3.202 270)
			(size 0.45 0.45)
			(layers "F.Cu" "F.Mask" "F.Paste")
			(net 1 "GND")
			(pinfunction "VSS")
			(pintype "passive")
		)
		(pad "D2" smd circle
			(at -3.202 -2.4 270)
			(size 0.45 0.45)
			(layers "F.Cu" "F.Mask" "F.Paste")
			(net 2 "VDDQ")
			(pinfunction "VDDQ")
			(pintype "power_in")
		)
		(pad "D3" smd circle
			(at -2.4 -2.4 270)
			(size 0.45 0.45)
			(layers "F.Cu" "F.Mask" "F.Paste")
			(net 1 "GND")
			(pinfunction "VSS")
			(pintype "passive")
		)
		(pad "D4" smd circle
			(at -1.601 -2.4 270)
			(size 0.45 0.45)
			(layers "F.Cu" "F.Mask" "F.Paste")
			(net 27 "DQS_N")
			(pinfunction "DQS_C")
			(pintype "bidirectional")
		)
		(pad "D8" smd circle
			(at 1.6 -2.4 270)
			(size 0.45 0.45)
			(layers "F.Cu" "F.Mask" "F.Paste")
			(net 39 "TDQS_N")
			(pinfunction "TDQS_C")
			(pintype "output")
		)
		(pad "D9" smd circle
			(at 2.398 -2.4 270)
			(size 0.45 0.45)
			(layers "F.Cu" "F.Mask" "F.Paste")
			(net 1 "GND")
			(pinfunction "VSS")
			(pintype "passive")
		)
		(pad "D10" smd circle
			(at 3.2 -2.4 270)
			(size 0.45 0.45)
			(layers "F.Cu" "F.Mask" "F.Paste")
			(net 2 "VDDQ")
			(pinfunction "VDDQ")
			(pintype "power_in")
		)
		(pad "E2" smd circle
			(at -3.202 -1.601 270)
			(size 0.45 0.45)
			(layers "F.Cu" "F.Mask" "F.Paste")
			(net 18 "VDD")
			(pinfunction "VDD")
			(pintype "power_in")
		)
		(pad "E3" smd circle
			(at -2.4 -1.601 270)
			(size 0.45 0.45)
			(layers "F.Cu" "F.Mask" "F.Paste")
			(net 31 "DQ4")
			(pinfunction "DQ4")
			(pintype "bidirectional")
		)
		(pad "E4" smd circle
			(at -1.601 -1.601 270)
			(size 0.45 0.45)
			(layers "F.Cu" "F.Mask" "F.Paste")
			(net 29 "DQ6")
			(pinfunction "DQ6")
			(pintype "bidirectional")
		)
		(pad "E8" smd circle
			(at 1.6 -1.601 270)
			(size 0.45 0.45)
			(layers "F.Cu" "F.Mask" "F.Paste")
			(net 28 "DQ7")
			(pinfunction "DQ7")
			(pintype "bidirectional")
		)
		(pad "E9" smd circle
			(at 2.398 -1.601 270)
			(size 0.45 0.45)
			(layers "F.Cu" "F.Mask" "F.Paste")
			(net 30 "DQ5")
			(pinfunction "DQ5")
			(pintype "bidirectional")
		)
		(pad "E10" smd circle
			(at 3.2 -1.601 270)
			(size 0.45 0.45)
			(layers "F.Cu" "F.Mask" "F.Paste")
			(net 18 "VDD")
			(pinfunction "VDD")
			(pintype "power_in")
		)
		(pad "F2" smd circle
			(at -3.202 -0.804 270)
			(size 0.45 0.45)
			(layers "F.Cu" "F.Mask" "F.Paste")
			(net 1 "GND")
			(pinfunction "VSS")
			(pintype "passive")
		)
		(pad "F3" smd circle
			(at -2.4 -0.804 270)
			(size 0.45 0.45)
			(layers "F.Cu" "F.Mask" "F.Paste")
			(net 2 "VDDQ")
			(pinfunction "VDDQ")
			(pintype "power_in")
		)
		(pad "F4" smd circle
			(at -1.601 -0.804 270)
			(size 0.45 0.45)
			(layers "F.Cu" "F.Mask" "F.Paste")
			(net 1 "GND")
			(pinfunction "VSS")
			(pintype "passive")
		)
		(pad "F8" smd circle
			(at 1.6 -0.804 270)
			(size 0.45 0.45)
			(layers "F.Cu" "F.Mask" "F.Paste")
			(net 1 "GND")
			(pinfunction "VSS")
			(pintype "passive")
		)
		(pad "F9" smd circle
			(at 2.398 -0.804 270)
			(size 0.45 0.45)
			(layers "F.Cu" "F.Mask" "F.Paste")
			(net 2 "VDDQ")
			(pinfunction "VDDQ")
			(pintype "power_in")
		)
		(pad "F10" smd circle
			(at 3.2 -0.804 270)
			(size 0.45 0.45)
			(layers "F.Cu" "F.Mask" "F.Paste")
			(net 1 "GND")
			(pinfunction "VSS")
			(pintype "passive")
		)
		(pad "G2" smd circle
			(at -3.202 0 270)
			(size 0.45 0.45)
			(layers "F.Cu" "F.Mask" "F.Paste")
			(net 58 "/DDR5/R_ODT_CA_A")
			(pinfunction "CA_ODT")
			(pintype "input")
		)
		(pad "G3" smd circle
			(at -2.4 0 270)
			(size 0.45 0.45)
			(layers "F.Cu" "F.Mask" "F.Paste")
			(net 63 "/DDR5/R_MIR")
			(pinfunction "MIR")
			(pintype "input")
		)
		(pad "G4" smd circle
			(at -1.601 0 270)
			(size 0.45 0.45)
			(layers "F.Cu" "F.Mask" "F.Paste")
			(net 18 "VDD")
			(pinfunction "VDD")
			(pintype "power_in")
		)
		(pad "G8" smd circle
			(at 1.6 0 270)
			(size 0.45 0.45)
			(layers "F.Cu" "F.Mask" "F.Paste")
			(net 42 "CLK_P")
			(pinfunction "CK_T")
			(pintype "input")
		)
		(pad "G9" smd circle
			(at 2.398 0 270)
			(size 0.45 0.45)
			(layers "F.Cu" "F.Mask" "F.Paste")
			(net 2 "VDDQ")
			(pinfunction "VDDQ")
			(pintype "power_in")
		)
		(pad "G10" smd circle
			(at 3.2 0 270)
			(size 0.45 0.45)
			(layers "F.Cu" "F.Mask" "F.Paste")
			(net 64 "/DDR5/R_TEN")
			(pinfunction "TEN")
			(pintype "input")
		)
		(pad "H2" smd circle
			(at -3.202 0.8 270)
			(size 0.45 0.45)
			(layers "F.Cu" "F.Mask" "F.Paste")
			(net 59 "/DDR5/R_ALERT_N")
			(pinfunction "ALERT_N")
			(pintype "bidirectional")
		)
		(pad "H3" smd circle
			(at -2.4 0.8 270)
			(size 0.45 0.45)
			(layers "F.Cu" "F.Mask" "F.Paste")
			(net 1 "GND")
			(pinfunction "VSS")
			(pintype "passive")
		)
		(pad "H4" smd circle
			(at -1.601 0.8 270)
			(size 0.45 0.45)
			(layers "F.Cu" "F.Mask" "F.Paste")
			(net 17 "CS_N")
			(pinfunction "CS_N")
			(pintype "input")
		)
		(pad "H8" smd circle
			(at 1.6 0.8 270)
			(size 0.45 0.45)
			(layers "F.Cu" "F.Mask" "F.Paste")
			(net 44 "CLK_N")
			(pinfunction "CK_C")
			(pintype "input")
		)
		(pad "H9" smd circle
			(at 2.398 0.8 270)
			(size 0.45 0.45)
			(layers "F.Cu" "F.Mask" "F.Paste")
			(net 1 "GND")
			(pinfunction "VSS")
			(pintype "passive")
		)
		(pad "H10" smd circle
			(at 3.2 0.8 270)
			(size 0.45 0.45)
			(layers "F.Cu" "F.Mask" "F.Paste")
			(net 18 "VDD")
			(pinfunction "VDD")
			(pintype "power_in")
		)
		(pad "J2" smd circle
			(at -3.202 1.6 270)
			(size 0.45 0.45)
			(layers "F.Cu" "F.Mask" "F.Paste")
			(net 2 "VDDQ")
			(pinfunction "VDDQ")
			(pintype "power_in")
		)
		(pad "J3" smd circle
			(at -2.4 1.6 270)
			(size 0.45 0.45)
			(layers "F.Cu" "F.Mask" "F.Paste")
			(net 48 "CA4")
			(pinfunction "CA4")
			(pintype "bidirectional")
		)
		(pad "J4" smd circle
			(at -1.601 1.6 270)
			(size 0.45 0.45)
			(layers "F.Cu" "F.Mask" "F.Paste")
			(net 24 "CA0")
			(pinfunction "CA0")
			(pintype "bidirectional")
		)
		(pad "J8" smd circle
			(at 1.6 1.6 270)
			(size 0.45 0.45)
			(layers "F.Cu" "F.Mask" "F.Paste")
			(net 22 "CA1")
			(pinfunction "CA1")
			(pintype "bidirectional")
		)
		(pad "J9" smd circle
			(at 2.398 1.6 270)
			(size 0.45 0.45)
			(layers "F.Cu" "F.Mask" "F.Paste")
			(net 49 "CA5")
			(pinfunction "CA5")
			(pintype "bidirectional")
		)
		(pad "J10" smd circle
			(at 3.2 1.6 270)
			(size 0.45 0.45)
			(layers "F.Cu" "F.Mask" "F.Paste")
			(net 2 "VDDQ")
			(pinfunction "VDDQ")
			(pintype "power_in")
		)
		(pad "K2" smd circle
			(at -3.202 2.398 270)
			(size 0.45 0.45)
			(layers "F.Cu" "F.Mask" "F.Paste")
			(net 18 "VDD")
			(pinfunction "VDD")
			(pintype "power_in")
		)
		(pad "K3" smd circle
			(at -2.4 2.398 270)
			(size 0.45 0.45)
			(layers "F.Cu" "F.Mask" "F.Paste")
			(net 40 "CA6")
			(pinfunction "CA6")
			(pintype "bidirectional")
		)
		(pad "K4" smd circle
			(at -1.601 2.398 270)
			(size 0.45 0.45)
			(layers "F.Cu" "F.Mask" "F.Paste")
			(net 46 "CA2")
			(pinfunction "CA2")
			(pintype "bidirectional")
		)
		(pad "K8" smd circle
			(at 1.6 2.398 270)
			(size 0.45 0.45)
			(layers "F.Cu" "F.Mask" "F.Paste")
			(net 47 "CA3")
			(pinfunction "CA3")
			(pintype "bidirectional")
		)
		(pad "K9" smd circle
			(at 2.398 2.398 270)
			(size 0.45 0.45)
			(layers "F.Cu" "F.Mask" "F.Paste")
			(net 41 "CA7")
			(pinfunction "CA7")
			(pintype "bidirectional")
		)
		(pad "K10" smd circle
			(at 3.2 2.398 270)
			(size 0.45 0.45)
			(layers "F.Cu" "F.Mask" "F.Paste")
			(net 18 "VDD")
			(pinfunction "VDD")
			(pintype "power_in")
		)
		(pad "L2" smd circle
			(at -3.202 3.2 270)
			(size 0.45 0.45)
			(layers "F.Cu" "F.Mask" "F.Paste")
			(net 2 "VDDQ")
			(pinfunction "VDDQ")
			(pintype "power_in")
		)
		(pad "L3" smd circle
			(at -2.4 3.2 270)
			(size 0.45 0.45)
			(layers "F.Cu" "F.Mask" "F.Paste")
			(net 1 "GND")
			(pinfunction "VSS")
			(pintype "passive")
		)
		(pad "L4" smd circle
			(at -1.601 3.2 270)
			(size 0.45 0.45)
			(layers "F.Cu" "F.Mask" "F.Paste")
			(net 43 "CA8")
			(pinfunction "CA8")
			(pintype "bidirectional")
		)
		(pad "L8" smd circle
			(at 1.6 3.2 270)
			(size 0.45 0.45)
			(layers "F.Cu" "F.Mask" "F.Paste")
			(net 45 "CA9")
			(pinfunction "CA9")
			(pintype "bidirectional")
		)
		(pad "L9" smd circle
			(at 2.398 3.2 270)
			(size 0.45 0.45)
			(layers "F.Cu" "F.Mask" "F.Paste")
			(net 1 "GND")
			(pinfunction "VSS")
			(pintype "passive")
		)
		(pad "L10" smd circle
			(at 3.2 3.2 270)
			(size 0.45 0.45)
			(layers "F.Cu" "F.Mask" "F.Paste")
			(net 2 "VDDQ")
			(pinfunction "VDDQ")
			(pintype "power_in")
		)
		(pad "M2" smd circle
			(at -3.202 3.999 270)
			(size 0.45 0.45)
			(layers "F.Cu" "F.Mask" "F.Paste")
			(net 62 "/DDR5/R_CAI")
			(pinfunction "CAI")
			(pintype "input")
		)
		(pad "M3" smd circle
			(at -2.4 3.999 270)
			(size 0.45 0.45)
			(layers "F.Cu" "F.Mask" "F.Paste")
			(net 32 "CA10")
			(pinfunction "CA10")
			(pintype "bidirectional")
		)
		(pad "M4" smd circle
			(at -1.601 3.999 270)
			(size 0.45 0.45)
			(layers "F.Cu" "F.Mask" "F.Paste")
			(net 34 "CA12")
			(pinfunction "CA12")
			(pintype "bidirectional")
		)
		(pad "M8" smd circle
			(at 1.6 3.999 270)
			(size 0.45 0.45)
			(layers "F.Cu" "F.Mask" "F.Paste")
			(net 35 "CA13")
			(pinfunction "CA13")
			(pintype "bidirectional")
		)
		(pad "M9" smd circle
			(at 2.398 3.999 270)
			(size 0.45 0.45)
			(layers "F.Cu" "F.Mask" "F.Paste")
			(net 33 "CA11")
			(pinfunction "CA11")
			(pintype "bidirectional")
		)
		(pad "M10" smd circle
			(at 3.2 3.999 270)
			(size 0.45 0.45)
			(layers "F.Cu" "F.Mask" "F.Paste")
			(net 60 "/DDR5/R_RESET_N")
			(pinfunction "RESET_N")
			(pintype "input")
		)
		(pad "N1" smd circle
			(at -4 4.799 270)
			(size 0.45 0.45)
			(layers "F.Cu" "F.Mask" "F.Paste")
			(net 221 "unconnected-(U1-DNU-PadN1)")
			(pinfunction "DNU")
			(pintype "no_connect")
		)
		(pad "N2" smd circle
			(at -3.202 4.799 270)
			(size 0.45 0.45)
			(layers "F.Cu" "F.Mask" "F.Paste")
			(net 18 "VDD")
			(pinfunction "VDD")
			(pintype "power_in")
		)
		(pad "N3" smd circle
			(at -2.4 4.799 270)
			(size 0.45 0.45)
			(layers "F.Cu" "F.Mask" "F.Paste")
			(net 1 "GND")
			(pinfunction "VSS")
			(pintype "passive")
		)
		(pad "N4" smd circle
			(at -1.601 4.799 270)
			(size 0.45 0.45)
			(layers "F.Cu" "F.Mask" "F.Paste")
			(net 18 "VDD")
			(pinfunction "VDD")
			(pintype "power_in")
		)
		(pad "N8" smd circle
			(at 1.6 4.799 270)
			(size 0.45 0.45)
			(layers "F.Cu" "F.Mask" "F.Paste")
			(net 19 "VPP")
			(pinfunction "VPP")
			(pintype "power_in")
		)
		(pad "N9" smd circle
			(at 2.398 4.799 270)
			(size 0.45 0.45)
			(layers "F.Cu" "F.Mask" "F.Paste")
			(net 1 "GND")
			(pinfunction "VSS")
			(pintype "passive")
		)
		(pad "N10" smd circle
			(at 3.2 4.799 270)
			(size 0.45 0.45)
			(layers "F.Cu" "F.Mask" "F.Paste")
			(net 18 "VDD")
			(pinfunction "VDD")
			(pintype "power_in")
		)
		(pad "N11" smd circle
			(at 3.999 4.799 270)
			(size 0.45 0.45)
			(layers "F.Cu" "F.Mask" "F.Paste")
			(net 222 "unconnected-(U1-DNU-PadN11)")
			(pinfunction "DNU")
			(pintype "no_connect")
		)
	)
)
